(kicad_pcb
	(version 20260206)
	(generator "pcbnew")
	(generator_version "10.0")
	(general
		(thickness 1.6)
		(legacy_teardrops no)
	)
	(paper "A4")
	(title_block
		(title "Bryce Canyon_IOM_IOC_16318-2_OCP.brd")
		(comment 1 "Bryce Canyon / footprints 1546-1553 of 1605")
	)
	(layers
		(0 "F.Cu" signal "TOP")
		(4 "In1.Cu" signal "L2GND")
		(6 "In2.Cu" signal "L3")
		(8 "In3.Cu" signal "L4VCC")
		(10 "In4.Cu" signal "L5VCC")
		(12 "In5.Cu" signal "L6")
		(14 "In6.Cu" signal "L7GND")
		(2 "B.Cu" signal "BOTTOM")
		(9 "F.Adhes" user "F.Adhesive")
		(11 "B.Adhes" user "B.Adhesive")
		(13 "F.Paste" user "Package Geometry/Pastemask Top")
		(15 "B.Paste" user "Package Geometry/Pastemask Bottom")
		(5 "F.SilkS" user "Ref Des/Silkscreen Top")
		(7 "B.SilkS" user "Ref Des/Silkscreen Bottom")
		(1 "F.Mask" user "Board Geometry/Soldermask Top")
		(3 "B.Mask" user "Board Geometry/Soldermask Bottom")
		(17 "Dwgs.User" user "User.Drawings")
		(19 "Cmts.User" user "User.Comments")
		(21 "Eco1.User" user "User.Eco1")
		(23 "Eco2.User" user "User.Eco2")
		(25 "Edge.Cuts" user "Board Geometry/Outline")
		(27 "Margin" user)
		(31 "F.CrtYd" user "Package Geometry/Place Bound Top")
		(29 "B.CrtYd" user "Package Geometry/Place Bound Bottom")
		(35 "F.Fab" user "Ref Des/Assembly Top")
		(33 "B.Fab" user "Ref Des/Assembly Bottom")
	)
	(footprint ""
		(layer "B.Cu")
		(at 193.9798 -64.8208 90)
		(property "Reference" "C400"
			(at 0 0 90)
			(layer "B.SilkS")
			(hide yes)
			(effects
				(font
					(size 1.27 1.27)
				)
				(justify mirror)
			)
		)
		(property "Value" "SCD1U6D3V1KX-GP"
			(at 2.8321 -1.7399 90)
			(unlocked yes)
			(layer "B.Fab")
			(hide yes)
			(effects
				(font
					(size 1.016 1.016)
					(thickness 0.1524)
				)
				(justify mirror)
			)
		)
		(property "Device Type" "C0201H13"
			(at 2.8321 -3.2639 90)
			(unlocked yes)
			(layer "B.Fab")
			(hide yes)
			(effects
				(font
					(size 1.016 1.016)
					(thickness 0.1524)
				)
				(justify mirror)
			)
		)
		(duplicate_pad_numbers_are_jumpers no)
		(fp_rect
			(start 0.2794 0.6477)
			(end -0.2794 -0.6477)
			(stroke
				(width 0)
				(type default)
			)
			(fill no)
			(layer "B.CrtYd")
		)
		(fp_rect
			(start 0.2794 0.6477)
			(end -0.2794 -0.6477)
			(stroke
				(width 0)
				(type default)
			)
			(fill no)
			(layer "B.Fab")
		)
		(pad "1" smd custom
			(at 0 -0.2794 270)
			(size 0.0762 0.0762)
			(layers "B.Cu" "B.Mask" "B.Paste")
			(net "P0V975")
			(options
				(clearance outline)
				(anchor circle)
			)
			(primitives
				(gr_poly
					(pts
						(arc
							(start 0.1524 0.127)
							(mid 0.137521 0.162921)
							(end 0.1016 0.1778)
						)
						(arc
							(start -0.1016 0.1778)
							(mid -0.137521 0.162921)
							(end -0.1524 0.127)
						)
						(arc
							(start -0.1524 -0.127)
							(mid -0.137521 -0.162921)
							(end -0.1016 -0.1778)
						)
						(arc
							(start 0.1016 -0.1778)
							(mid 0.137521 -0.162921)
							(end 0.1524 -0.127)
						)
					)
					(width 0)
					(fill yes)
				)
			)
		)
		(pad "2" smd custom
			(at 0 0.2794 270)
			(size 0.0762 0.0762)
			(layers "B.Cu" "B.Mask" "B.Paste")
			(net "GND")
			(options
				(clearance outline)
				(anchor circle)
			)
			(primitives
				(gr_poly
					(pts
						(arc
							(start 0.1524 0.127)
							(mid 0.137521 0.162921)
							(end 0.1016 0.1778)
						)
						(arc
							(start -0.1016 0.1778)
							(mid -0.137521 0.162921)
							(end -0.1524 0.127)
						)
						(arc
							(start -0.1524 -0.127)
							(mid -0.137521 -0.162921)
							(end -0.1016 -0.1778)
						)
						(arc
							(start 0.1016 -0.1778)
							(mid 0.137521 -0.162921)
							(end 0.1524 -0.127)
						)
					)
					(width 0)
					(fill yes)
				)
			)
		)
	)
	(footprint ""
		(layer "B.Cu")
		(at 188.078872 -74.793856 -90)
		(property "Reference" "C472"
			(at 0 0 90)
			(layer "B.SilkS")
			(hide yes)
			(effects
				(font
					(size 1.27 1.27)
				)
				(justify mirror)
			)
		)
		(property "Value" "SCD1U16V2KX-3GP"
			(at -1.1811 -2.7051 270)
			(unlocked yes)
			(layer "B.Fab")
			(hide yes)
			(effects
				(font
					(size 1.016 1.016)
					(thickness 0.1524)
				)
				(justify mirror)
			)
		)
		(property "Device Type" "C402H22"
			(at -1.1811 -4.2291 270)
			(unlocked yes)
			(layer "B.Fab")
			(hide yes)
			(effects
				(font
					(size 1.016 1.016)
					(thickness 0.1524)
				)
				(justify mirror)
			)
		)
		(duplicate_pad_numbers_are_jumpers no)
		(fp_rect
			(start 0.4318 0.9525)
			(end -0.4318 -0.9525)
			(stroke
				(width 0)
				(type default)
			)
			(fill no)
			(layer "B.CrtYd")
		)
		(fp_rect
			(start 0.4318 0.9525)
			(end -0.4318 -0.9525)
			(stroke
				(width 0)
				(type default)
			)
			(fill no)
			(layer "B.Fab")
		)
		(pad "1" smd custom
			(at 0 -0.4445 90)
			(size 0.1524 0.1524)
			(layers "B.Cu" "B.Mask" "B.Paste")
			(net "P1V8")
			(options
				(clearance outline)
				(anchor circle)
			)
			(primitives
				(gr_poly
					(pts
						(arc
							(start 0.3048 0.2032)
							(mid 0.275042 0.275042)
							(end 0.2032 0.3048)
						)
						(arc
							(start -0.2032 0.3048)
							(mid -0.275042 0.275042)
							(end -0.3048 0.2032)
						)
						(arc
							(start -0.3048 -0.2032)
							(mid -0.275042 -0.275042)
							(end -0.2032 -0.3048)
						)
						(arc
							(start 0.2032 -0.3048)
							(mid 0.275042 -0.275042)
							(end 0.3048 -0.2032)
						)
					)
					(width 0)
					(fill yes)
				)
			)
		)
		(pad "2" smd custom
			(at 0 0.4445 90)
			(size 0.1524 0.1524)
			(layers "B.Cu" "B.Mask" "B.Paste")
			(net "GND")
			(options
				(clearance outline)
				(anchor circle)
			)
			(primitives
				(gr_poly
					(pts
						(arc
							(start 0.3048 0.2032)
							(mid 0.275042 0.275042)
							(end 0.2032 0.3048)
						)
						(arc
							(start -0.2032 0.3048)
							(mid -0.275042 0.275042)
							(end -0.3048 0.2032)
						)
						(arc
							(start -0.3048 -0.2032)
							(mid -0.275042 -0.275042)
							(end -0.2032 -0.3048)
						)
						(arc
							(start 0.2032 -0.3048)
							(mid 0.275042 -0.275042)
							(end 0.3048 -0.2032)
						)
					)
					(width 0)
					(fill yes)
				)
			)
		)
	)
	(footprint ""
		(layer "B.Cu")
		(at 190.831978 -62.18047 90)
		(property "Reference" "C414"
			(at 0 0 90)
			(layer "B.SilkS")
			(hide yes)
			(effects
				(font
					(size 1.27 1.27)
				)
				(justify mirror)
			)
		)
		(property "Value" "SCD1U6D3V1KX-GP"
			(at 2.8321 -1.7399 90)
			(unlocked yes)
			(layer "B.Fab")
			(hide yes)
			(effects
				(font
					(size 1.016 1.016)
					(thickness 0.1524)
				)
				(justify mirror)
			)
		)
		(property "Device Type" "C0201H13"
			(at 2.8321 -3.2639 90)
			(unlocked yes)
			(layer "B.Fab")
			(hide yes)
			(effects
				(font
					(size 1.016 1.016)
					(thickness 0.1524)
				)
				(justify mirror)
			)
		)
		(duplicate_pad_numbers_are_jumpers no)
		(fp_rect
			(start 0.2794 0.6477)
			(end -0.2794 -0.6477)
			(stroke
				(width 0)
				(type default)
			)
			(fill no)
			(layer "B.CrtYd")
		)
		(fp_rect
			(start 0.2794 0.6477)
			(end -0.2794 -0.6477)
			(stroke
				(width 0)
				(type default)
			)
			(fill no)
			(layer "B.Fab")
		)
		(pad "1" smd custom
			(at 0 -0.2794 270)
			(size 0.0762 0.0762)
			(layers "B.Cu" "B.Mask" "B.Paste")
			(net "P0V975")
			(options
				(clearance outline)
				(anchor circle)
			)
			(primitives
				(gr_poly
					(pts
						(arc
							(start 0.1524 0.127)
							(mid 0.137521 0.162921)
							(end 0.1016 0.1778)
						)
						(arc
							(start -0.1016 0.1778)
							(mid -0.137521 0.162921)
							(end -0.1524 0.127)
						)
						(arc
							(start -0.1524 -0.127)
							(mid -0.137521 -0.162921)
							(end -0.1016 -0.1778)
						)
						(arc
							(start 0.1016 -0.1778)
							(mid 0.137521 -0.162921)
							(end 0.1524 -0.127)
						)
					)
					(width 0)
					(fill yes)
				)
			)
		)
		(pad "2" smd custom
			(at 0 0.2794 270)
			(size 0.0762 0.0762)
			(layers "B.Cu" "B.Mask" "B.Paste")
			(net "GND")
			(options
				(clearance outline)
				(anchor circle)
			)
			(primitives
				(gr_poly
					(pts
						(arc
							(start 0.1524 0.127)
							(mid 0.137521 0.162921)
							(end 0.1016 0.1778)
						)
						(arc
							(start -0.1016 0.1778)
							(mid -0.137521 0.162921)
							(end -0.1524 0.127)
						)
						(arc
							(start -0.1524 -0.127)
							(mid -0.137521 -0.162921)
							(end -0.1016 -0.1778)
						)
						(arc
							(start 0.1016 -0.1778)
							(mid 0.137521 -0.162921)
							(end 0.1524 -0.127)
						)
					)
					(width 0)
					(fill yes)
				)
			)
		)
	)
	(footprint ""
		(layer "B.Cu")
		(at 191.8462 -66.6369 -90)
		(property "Reference" "C425"
			(at 0 0 90)
			(layer "B.SilkS")
			(hide yes)
			(effects
				(font
					(size 1.27 1.27)
				)
				(justify mirror)
			)
		)
		(property "Value" "SC1KP50V2KX-1GP"
			(at -1.1811 -2.7051 270)
			(unlocked yes)
			(layer "B.Fab")
			(hide yes)
			(effects
				(font
					(size 1.016 1.016)
					(thickness 0.1524)
				)
				(justify mirror)
			)
		)
		(property "Device Type" "C402H22"
			(at -1.1811 -4.2291 270)
			(unlocked yes)
			(layer "B.Fab")
			(hide yes)
			(effects
				(font
					(size 1.016 1.016)
					(thickness 0.1524)
				)
				(justify mirror)
			)
		)
		(duplicate_pad_numbers_are_jumpers no)
		(fp_rect
			(start 0.4318 0.9525)
			(end -0.4318 -0.9525)
			(stroke
				(width 0)
				(type default)
			)
			(fill no)
			(layer "B.CrtYd")
		)
		(fp_rect
			(start 0.4318 0.9525)
			(end -0.4318 -0.9525)
			(stroke
				(width 0)
				(type default)
			)
			(fill no)
			(layer "B.Fab")
		)
		(pad "1" smd custom
			(at 0 -0.4445 90)
			(size 0.1524 0.1524)
			(layers "B.Cu" "B.Mask" "B.Paste")
			(net "P0V975")
			(options
				(clearance outline)
				(anchor circle)
			)
			(primitives
				(gr_poly
					(pts
						(arc
							(start 0.3048 0.2032)
							(mid 0.275042 0.275042)
							(end 0.2032 0.3048)
						)
						(arc
							(start -0.2032 0.3048)
							(mid -0.275042 0.275042)
							(end -0.3048 0.2032)
						)
						(arc
							(start -0.3048 -0.2032)
							(mid -0.275042 -0.275042)
							(end -0.2032 -0.3048)
						)
						(arc
							(start 0.2032 -0.3048)
							(mid 0.275042 -0.275042)
							(end 0.3048 -0.2032)
						)
					)
					(width 0)
					(fill yes)
				)
			)
		)
		(pad "2" smd custom
			(at 0 0.4445 90)
			(size 0.1524 0.1524)
			(layers "B.Cu" "B.Mask" "B.Paste")
			(net "GND")
			(options
				(clearance outline)
				(anchor circle)
			)
			(primitives
				(gr_poly
					(pts
						(arc
							(start 0.3048 0.2032)
							(mid 0.275042 0.275042)
							(end 0.2032 0.3048)
						)
						(arc
							(start -0.2032 0.3048)
							(mid -0.275042 0.275042)
							(end -0.3048 0.2032)
						)
						(arc
							(start -0.3048 -0.2032)
							(mid -0.275042 -0.275042)
							(end -0.2032 -0.3048)
						)
						(arc
							(start 0.2032 -0.3048)
							(mid 0.275042 -0.275042)
							(end 0.3048 -0.2032)
						)
					)
					(width 0)
					(fill yes)
				)
			)
		)
	)
	(footprint ""
		(layer "B.Cu")
		(at 41.91762 -136.94918)
		(property "Reference" "TP29"
			(at 0 0 0)
			(layer "B.SilkS")
			(hide yes)
			(effects
				(font
					(size 1.27 1.27)
				)
				(justify mirror)
			)
		)
		(property "Value" "TPAD28-2-GP"
			(at 0.0127 -1.6637 0)
			(unlocked yes)
			(layer "B.Fab")
			(hide yes)
			(effects
				(font
					(size 1.016 1.016)
					(thickness 0.1524)
				)
				(justify mirror)
			)
		)
		(property "Device Type" "TPAD28"
			(at 0.0127 -3.1877 0)
			(unlocked yes)
			(layer "B.Fab")
			(hide yes)
			(effects
				(font
					(size 1.016 1.016)
					(thickness 0.1524)
				)
				(justify mirror)
			)
		)
		(duplicate_pad_numbers_are_jumpers no)
		(fp_poly
			(pts
				(arc
					(start 0.3556 0)
					(mid -0.3556 0)
					(end 0.3556 0)
				)
			)
			(stroke
				(width 0)
				(type default)
			)
			(fill no)
			(layer "B.CrtYd")
		)
		(fp_poly
			(pts
				(arc
					(start 0.6096 0)
					(mid -0.6096 0)
					(end 0.6096 0)
				)
			)
			(stroke
				(width 0)
				(type default)
			)
			(fill no)
			(layer "B.Fab")
		)
		(pad "1" smd circle
			(at 0 0 180)
			(size 0.7112 0.7112)
			(layers "B.Cu" "B.Mask" "B.Paste")
			(net "TP_BMC_GPIOR5")
		)
	)
	(footprint ""
		(layer "B.Cu")
		(at 12.11199 -141.008862 90)
		(property "Reference" "R255"
			(at 0 0 90)
			(layer "B.SilkS")
			(hide yes)
			(effects
				(font
					(size 1.27 1.27)
				)
				(justify mirror)
			)
		)
		(property "Value" "120R2F-GP"
			(at -0.064008 -3.993896 90)
			(unlocked yes)
			(layer "B.Fab")
			(hide yes)
			(effects
				(font
					(size 1.016 1.016)
					(thickness 0.1524)
				)
				(justify mirror)
			)
		)
		(property "Device Type" "R402H16"
			(at -0.064008 -5.517896 90)
			(unlocked yes)
			(layer "B.Fab")
			(hide yes)
			(effects
				(font
					(size 1.016 1.016)
					(thickness 0.1524)
				)
				(justify mirror)
			)
		)
		(duplicate_pad_numbers_are_jumpers no)
		(fp_line
			(start 0.508 -0.9398)
			(end 0.508 0.9398)
			(stroke
				(width 0.1524)
				(type default)
			)
			(layer "B.SilkS")
		)
		(fp_line
			(start -0.508 -0.9398)
			(end 0.508 -0.9398)
			(stroke
				(width 0.1524)
				(type default)
			)
			(layer "B.SilkS")
		)
		(fp_rect
			(start 0.508 0.9398)
			(end -0.508 -0.9398)
			(stroke
				(width 0)
				(type default)
			)
			(fill no)
			(layer "B.CrtYd")
		)
		(fp_rect
			(start 0.508 0.9398)
			(end -0.508 -0.9398)
			(stroke
				(width 0)
				(type default)
			)
			(fill no)
			(layer "B.Fab")
		)
		(pad "1" smd custom
			(at 0 -0.4445 270)
			(size 0.1397 0.1397)
			(layers "B.Cu" "B.Mask" "B.Paste")
			(net "MEMA_10")
			(options
				(clearance outline)
				(anchor circle)
			)
			(primitives
				(gr_poly
					(pts
						(arc
							(start -0.1778 0.2794)
							(mid -0.249642 0.249642)
							(end -0.2794 0.1778)
						)
						(arc
							(start -0.2794 -0.1778)
							(mid -0.249642 -0.249642)
							(end -0.1778 -0.2794)
						)
						(arc
							(start 0.1778 -0.2794)
							(mid 0.249642 -0.249642)
							(end 0.2794 -0.1778)
						)
						(arc
							(start 0.2794 0.1778)
							(mid 0.249642 0.249642)
							(end 0.1778 0.2794)
						)
					)
					(width 0)
					(fill yes)
				)
			)
		)
		(pad "2" smd custom
			(at 0 0.4445 270)
			(size 0.1397 0.1397)
			(layers "B.Cu" "B.Mask" "B.Paste")
			(net "P1V2_STBY")
			(options
				(clearance outline)
				(anchor circle)
			)
			(primitives
				(gr_poly
					(pts
						(arc
							(start -0.1778 0.2794)
							(mid -0.249642 0.249642)
							(end -0.2794 0.1778)
						)
						(arc
							(start -0.2794 -0.1778)
							(mid -0.249642 -0.249642)
							(end -0.1778 -0.2794)
						)
						(arc
							(start 0.1778 -0.2794)
							(mid 0.249642 -0.249642)
							(end 0.2794 -0.1778)
						)
						(arc
							(start 0.2794 0.1778)
							(mid 0.249642 0.249642)
							(end 0.1778 0.2794)
						)
					)
					(width 0)
					(fill yes)
				)
			)
		)
	)
	(footprint ""
		(layer "B.Cu")
		(at 50.01006 -143.6624 180)
		(property "Reference" "R363"
			(at 0 0 0)
			(layer "B.SilkS")
			(hide yes)
			(effects
				(font
					(size 1.27 1.27)
				)
				(justify mirror)
			)
		)
		(property "Value" "4K7R2F-GP"
			(at -0.064008 -3.993896 180)
			(unlocked yes)
			(layer "B.Fab")
			(hide yes)
			(effects
				(font
					(size 1.016 1.016)
					(thickness 0.1524)
				)
				(justify mirror)
			)
		)
		(property "Device Type" "R402H16"
			(at -0.064008 -5.517896 180)
			(unlocked yes)
			(layer "B.Fab")
			(hide yes)
			(effects
				(font
					(size 1.016 1.016)
					(thickness 0.1524)
				)
				(justify mirror)
			)
		)
		(duplicate_pad_numbers_are_jumpers no)
		(fp_line
			(start 0.508 -0.9398)
			(end 0.508 0.9398)
			(stroke
				(width 0.1524)
				(type default)
			)
			(layer "B.SilkS")
		)
		(fp_line
			(start -0.508 -0.9398)
			(end 0.508 -0.9398)
			(stroke
				(width 0.1524)
				(type default)
			)
			(layer "B.SilkS")
		)
		(fp_rect
			(start 0.508 0.9398)
			(end -0.508 -0.9398)
			(stroke
				(width 0)
				(type default)
			)
			(fill no)
			(layer "B.CrtYd")
		)
		(fp_rect
			(start 0.508 0.9398)
			(end -0.508 -0.9398)
			(stroke
				(width 0)
				(type default)
			)
			(fill no)
			(layer "B.Fab")
		)
		(pad "1" smd custom
			(at 0 -0.4445)
			(size 0.1397 0.1397)
			(layers "B.Cu" "B.Mask" "B.Paste")
			(net "JTAG_BMC_TRST_N")
			(options
				(clearance outline)
				(anchor circle)
			)
			(primitives
				(gr_poly
					(pts
						(arc
							(start -0.1778 0.2794)
							(mid -0.249642 0.249642)
							(end -0.2794 0.1778)
						)
						(arc
							(start -0.2794 -0.1778)
							(mid -0.249642 -0.249642)
							(end -0.1778 -0.2794)
						)
						(arc
							(start 0.1778 -0.2794)
							(mid 0.249642 -0.249642)
							(end 0.2794 -0.1778)
						)
						(arc
							(start 0.2794 0.1778)
							(mid 0.249642 0.249642)
							(end 0.1778 0.2794)
						)
					)
					(width 0)
					(fill yes)
				)
			)
		)
		(pad "2" smd custom
			(at 0 0.4445)
			(size 0.1397 0.1397)
			(layers "B.Cu" "B.Mask" "B.Paste")
			(net "GND")
			(options
				(clearance outline)
				(anchor circle)
			)
			(primitives
				(gr_poly
					(pts
						(arc
							(start -0.1778 0.2794)
							(mid -0.249642 0.249642)
							(end -0.2794 0.1778)
						)
						(arc
							(start -0.2794 -0.1778)
							(mid -0.249642 -0.249642)
							(end -0.1778 -0.2794)
						)
						(arc
							(start 0.1778 -0.2794)
							(mid 0.249642 -0.249642)
							(end 0.2794 -0.1778)
						)
						(arc
							(start 0.2794 0.1778)
							(mid 0.249642 0.249642)
							(end 0.1778 0.2794)
						)
					)
					(width 0)
					(fill yes)
				)
			)
		)
	)
	(footprint ""
		(layer "B.Cu")
		(at 193.1162 -47.0408 -90)
		(property "Reference" "C330"
			(at 0 0 90)
			(layer "B.SilkS")
			(hide yes)
			(effects
				(font
					(size 1.27 1.27)
				)
				(justify mirror)
			)
		)
		(property "Value" "SC22U6D3V3MX-9-GP-U"
			(at 0 -2.8194 270)
			(unlocked yes)
			(layer "B.Fab")
			(hide yes)
			(effects
				(font
					(size 1.016 1.016)
					(thickness 0.1524)
				)
				(justify mirror)
			)
		)
		(property "Device Type" "C603H40"
			(at 0 -4.3434 270)
			(unlocked yes)
			(layer "B.Fab")
			(hide yes)
			(effects
				(font
					(size 1.016 1.016)
					(thickness 0.1524)
				)
				(justify mirror)
			)
		)
		(duplicate_pad_numbers_are_jumpers no)
		(fp_line
			(start -0.508 0)
			(end 0.508 0)
			(stroke
				(width 0.2032)
				(type default)
			)
			(layer "B.SilkS")
		)
		(fp_rect
			(start 0.5842 1.3335)
			(end -0.5842 -1.3335)
			(stroke
				(width 0)
				(type default)
			)
			(fill no)
			(layer "B.CrtYd")
		)
		(fp_rect
			(start 0.5842 1.3335)
			(end -0.5842 -1.3335)
			(stroke
				(width 0)
				(type default)
			)
			(fill no)
			(layer "B.Fab")
		)
		(pad "1" smd custom
			(at 0 -0.762 90)
			(size 0.2159 0.2159)
			(layers "B.Cu" "B.Mask" "B.Paste")
			(net "HM40ADC_VDDA")
			(options
				(clearance outline)
				(anchor circle)
			)
			(primitives
				(gr_poly
					(pts
						(arc
							(start -0.3302 0.4318)
							(mid -0.402042 0.402042)
							(end -0.4318 0.3302)
						)
						(arc
							(start -0.4318 -0.3302)
							(mid -0.402042 -0.402042)
							(end -0.3302 -0.4318)
						)
						(arc
							(start 0.3302 -0.4318)
							(mid 0.402042 -0.402042)
							(end 0.4318 -0.3302)
						)
						(arc
							(start 0.4318 0.3302)
							(mid 0.402042 0.402042)
							(end 0.3302 0.4318)
						)
					)
					(width 0)
					(fill yes)
				)
			)
		)
		(pad "2" smd custom
			(at 0 0.762 90)
			(size 0.2159 0.2159)
			(layers "B.Cu" "B.Mask" "B.Paste")
			(net "GND")
			(options
				(clearance outline)
				(anchor circle)
			)
			(primitives
				(gr_poly
					(pts
						(arc
							(start -0.3302 0.4318)
							(mid -0.402042 0.402042)
							(end -0.4318 0.3302)
						)
						(arc
							(start -0.4318 -0.3302)
							(mid -0.402042 -0.402042)
							(end -0.3302 -0.4318)
						)
						(arc
							(start 0.3302 -0.4318)
							(mid 0.402042 -0.402042)
							(end 0.4318 -0.3302)
						)
						(arc
							(start 0.4318 0.3302)
							(mid 0.402042 0.402042)
							(end 0.3302 0.4318)
						)
					)
					(width 0)
					(fill yes)
				)
			)
		)
	)
)
